FILE_TYPE = CONNECTIVITY;
{Allegro Design Entry HDL 17.2-2016 S081 (4005846) 1/11/2022}
"PAGE_NUMBER" = 12;
0"NC";
1"P0V6_DDR_VREF_AUX\g";
2"P3V3_AUX\g";
3"P3V3_AUX\g";
4"PGPPA_BMC_AUX\g";
5"GND\g";
6"GND\g";
7"GND\g";
8"GND\g";
9"GND\g";
10"GND\g";
11"M_BMC_DDR4_MA<13:0>";
12"M_BMC_DDR4_DQ<15:0>";
13"SMB_BMC_MM3_R_SCL";
14"SMB_BMC_MM3_R_SDA";
15"SMB_BMC_MM4_R_SCL";
16"SMB_BMC_MM4_R_SDA";
17"SMB_BMC_MM5_R_SCL";
18"SMB_BMC_MM8_SCL";
19"SMB_BMC_MM8_SDA";
20"SMB_BMC_MM9_R_SCL";
21"SMB_BMC_MM9_R_SDA";
22"SMB_BMC_MM10_R_SCL";
23"SMB_BMC_MM10_R_SDA";
24"SMB_BMC_MM8_R_SCL";
25"SMB_BMC_MM8_R_SDA";
26"SMB_BMC_MM7_R_SDA";
27"SMB_BMC_MM6_SDA";
28"SMB_BMC_MM6_SCL";
29"SMB_BMC_MM4_SDA";
30"SMB_BMC_MM5_R_SDA";
31"SMB_BMC_MM6_R_SCL";
32"SMB_BMC_MM6_R_SDA";
33"SMB_BMC_MM7_R_SCL";
34"SMB_BMC_MM4_SCL";
35"SMB_BMC_MM3_SDA";
36"SMB_BMC_MM3_SCL";
37"SMB_BMC_MM2_SDA";
38"SMB_BMC_MM14_R_SDA";
39"SMB_BMC_MM14_SCL";
40"SMB_BMC_MM13_SDA";
41"SMB_BMC_MM13_SCL";
42"SMB_BMC_MM12_SDA";
43"SMB_BMC_MM12_SCL";
44"RST_PFR_OVR_RTC_R";
45"FM_PFR_DSW_PWROK_N";
46"SMB_BMC_MM14_SDA";
47"SMB_BMC_MM2_R_SDA";
48"SMB_BMC_MM2_R_SCL";
49"RST_ESPI_LPC_BMC_N";
50"BMC_EMMC_CLK";
51"IRQ_ESPI_LPC_SERIRQ_ALERT0_N";
52"ESPI_HOST_LPC_BMC_LFRAME_N_R";
53"BMC_EMMC_DT2";
54"BMC_EMMC_DT3";
55"BMC_EMMC_CD_N";
56"BMC_EMMC_WP_N";
57"UART_6_BMC_TXD";
58"ESPI_HOST_LPC_BMC_CLK_R";
59"BMC_EMMC_CMD";
60"BMC_EMMC_DT0";
61"BMC_EMMC_DT1";
62"UART_6_BMC_R_TXD";
63"BMC_EMMC_DT4";
64"BMC_EMMC_DT5";
65"BMC_EMMC_DT6";
66"BMC_EMMC_DT7";
67"SMB_BMC_ALERT15_N";
68"FM_BMC_DBP_PRESENT_N";
69"SGPIO_LD_1";
70"SGPIO_DI_1";
71"SMB_BMC_MM15_SCL";
72"SMB_BMC_MM15_SDA";
73"SMB_BMC_MM16_SDA";
74"RST_BMC_LPC_ESPI_N";
75"SMB_BMC_MM7_R_SDA";
76"SMB_BMC_MM7_SCL";
77"SMB_BMC_MM5_SDA";
78"ESPI_LPC_LAD0_IO0";
79"ESPI_LPC_LAD1_IO1";
80"ESPI_LPC_LAD2_IO2";
81"ESPI_LPC_LAD3_IO3";
82"SMB_BMC_MM1_SCL";
83"SMB_BMC_MM1_R_SDA";
84"SMB_BMC_MM1_R_SCL";
85"SMB_BMC_MM2_SCL";
86"SMB_BMC_MM1_SDA";
87"FM_TPM_PRSNT_1_N";
88"SMB_BMC_MM12_R_SDA";
89"SMB_BMC_MM14_R_SCL";
90"SMB_BMC_MM13_R_SDA";
91"SMB_BMC_MM13_R_SCL";
92"M_BMC_DDR4_MA<4>";
93"M_BMC_DDR4_MA<2>";
94"M_BMC_DDR4_MA<1>";
95"M_BMC_DDR4_MA<0>";
96"M_BMC_DDR4_MCS_N";
97"M_BMC_DDR4_MODT";
98"FM_THERMTRIP_DLY_LVC1_R_N";
99"UART_6_BMC_R_RXD";
100"P2E_GPU_TX_DN";
101"P2E_PCH_TX_DN";
102"P2E_PCH_TX_DP";
103"SMB_BMC_MM10_SDA";
104"SMB_BMC_MM9_SCL";
105"SMB_BMC_MM9_SDA";
106"SMB_BMC_MM10_SCL";
107"FM_THERMTRIP_DLY_LVC1_R_N";
108"SMB_BMC_MM5_SCL";
109"P2E_PCH_TX_C_DP";
110"P2E_PCH_TX_C_DN";
111"M_BMC_DDR4_DQ<12>";
112"M_BMC_DDR4_DQ<11>";
113"M_BMC_DDR4_DQ<10>";
114"M_BMC_DDR4_DQ<9>";
115"M_BMC_DDR4_DQ<8>";
116"M_BMC_DDR4_DQ<7>";
117"M_BMC_DDR4_DQ<6>";
118"M_BMC_DDR4_DQ<13>";
119"M_BMC_DDR4_DQ<5>";
120"M_BMC_DDR4_DQ<0>";
121"NC_DP_BMC_AUX_P";
122"NC_DP_BMC_AUX_N";
123"DP_BMC_HPD_3V3_BUF";
124"ESPI_HOST_LPC_BMC_CLK";
125"M_BMC_DDR4_DQ<14>";
126"M_BMC_DDR4_DQ<15>";
127"M_BMC_DDR4_DQS0_P";
128"M_BMC_DDR4_DQS1_P";
129"M_BMC_DDR4_DQS0_N";
130"ESPI_HOST_LPC_BMC_LFRAME_N";
131"SMB_BMC_MM16_R_SCL";
132"FM_BMC_DBP_PRESENT_R_N";
133"SGPIO_BMC_M1_CLK";
134"SGPIO_BMC_M1_LD";
135"SGPIO_BMC_M1_DO";
136"SGPIO_BMC_M1_DI";
137"SMB_BMC_MM15_R_SCL";
138"SMB_BMC_MM15_R_SDA";
139"RST_PLTRST_N";
140"SMB_BMC_MM10_R_SCL";
141"SMB_BMC_MM9_R_SDA";
142"SMB_BMC_MM9_R_SCL";
143"SMB_BMC_MM7_SDA";
144"SMB_BMC_MM5_R_SCL";
145"SMB_BMC_MM7_R_SCL";
146"SMB_BMC_MM5_R_SDA";
147"SMB_BMC_MM12_R_SCL";
148"M_BMC_DDR4_MDM1";
149"M_BMC_DDR4_MDM0";
150"M_BMC_DDR4_MBG1";
151"M_BMC_DDR4_MACT_N";
152"M_BMC_DDR4_MA<11>";
153"M_BMC_DDR4_MBA1";
154"P2E_GPU_TX_DP";
155"CLK_100M_PCH_DP";
156"FM_PCH_BMC_THERMTRIP_N";
157"FM_BMC_DBP_PRESENT_N";
158"RST_BMC_LPC_ESPI_N";
159"UART_6_BMC_RXD";
160"P2E_GPU_TX_C_DP";
161"P2E_GPU_TX_C_DN";
162"IRQ_BMC_LPC_SERIRQ_ESPI_GF";
163"SGPIO_CLK_1";
164"SGPIO_DO_1";
165"ESPI_HOST_LPC_BMC_LFRAME_N";
166"IRQ_BMC_LPC_SERIRQ_ESPI_GF";
167"SMB_BMC_MM16_R5_SDA";
168"SMB_BMC_MM16_SCL";
169"SMB_BMC_MM16_R_SDA";
170"RST_PLTRST_R_N";
171"SMB_BMC_MM10_R_SDA";
172"SMB_BMC_MM16_R5_SCL";
173"M_BMC_DDR4_DQS1_N";
174"M_BMC_DDR4_RST_N";
175"M_BMC_DDR4_MBA0";
176"M_BMC_DDR4_MWE_N";
177"M_BMC_DDR4_MCAS_N";
178"M_BMC_DDR4_MCKE";
179"M_BMC_DDR4_DQ<1>";
180"M_BMC_DDR4_DQ<2>";
181"M_BMC_DDR4_DQ<3>";
182"M_BMC_DDR4_DQ<4>";
183"M_BMC_DDR4_MRAS_N";
184"M_BMC_DDR4_MCLK_DP";
185"M_BMC_DDR4_MA<3>";
186"M_BMC_DDR4_MA<5>";
187"M_BMC_DDR4_MA<6>";
188"M_BMC_DDR4_MA<7>";
189"M_BMC_DDR4_MA<8>";
190"M_BMC_DDR4_MA<9>";
191"M_BMC_DDR4_MA<10>";
192"M_BMC_DDR4_MBG0";
193"M_BMC_DDR4_MCLK_DN";
194"NC_DP_BMC_TX1_N";
195"NC_DP_BMC_TX1_P";
196"NC_DP_BMC_TX0_N";
197"NC_DP_BMC_TX0_P";
198"P2E_GPU_RX_DN";
199"P2E_GPU_RX_DP";
200"CLK_100M_GPU_DN";
201"CLK_100M_GPU_DP";
202"P2E_PCH_RX_DN";
203"P2E_PCH_RX_DP";
204"CLK_100M_PCH_DN";
205"RST_PLTRST_N";
206"M_BMC_DDR4_MA<12>";
207"M_BMC_DDR4_MA<13>";
208"M_BMC_DDR4_ALERT_N";
209"IBMC_MIOZ";
210"ESPI_LPC_D0_IO0";
211"ESPI_LPC_D1_IO1";
212"ESPI_LPC_D3_IO3";
213"ESPI_LPC_D2_IO2";
%"UNIVERSAL_POWER"
"1","(-1875,-175)","0","logical_power","I1";
;
HDL_POWER"PGPPA_BMC_AUX"
CDS_LIB"logical_power";
"A"4;
%"TAP"
"1","(4175,2400)","0","standard","I107";
;
HDL_TAP"TRUE"
BODY_TYPE"PLUMBING"
CDS_LIB"standard";
"B \NAC \NWC"11;
"S \NAC"
BN"13"207;
%"TAP"
"1","(4175,2450)","0","standard","I108";
;
HDL_TAP"TRUE"
BODY_TYPE"PLUMBING"
CDS_LIB"standard";
"B \NAC \NWC"11;
"S \NAC"
BN"12"206;
%"TAP"
"1","(4175,2500)","0","standard","I109";
;
HDL_TAP"TRUE"
BODY_TYPE"PLUMBING"
CDS_LIB"standard";
"B \NAC \NWC"11;
"S \NAC"
BN"11"152;
%"TAP"
"1","(4175,2550)","0","standard","I110";
;
HDL_TAP"TRUE"
BODY_TYPE"PLUMBING"
CDS_LIB"standard";
"B \NAC \NWC"11;
"S \NAC"
BN"10"191;
%"TAP"
"1","(4175,2650)","0","standard","I111";
;
HDL_TAP"TRUE"
BODY_TYPE"PLUMBING"
CDS_LIB"standard";
"B \NAC \NWC"11;
"S \NAC"
BN"8"189;
%"TAP"
"1","(4175,2600)","0","standard","I112";
;
HDL_TAP"TRUE"
BODY_TYPE"PLUMBING"
CDS_LIB"standard";
"B \NAC \NWC"11;
"S \NAC"
BN"9"190;
%"TAP"
"1","(4175,2700)","0","standard","I113";
;
HDL_TAP"TRUE"
BODY_TYPE"PLUMBING"
CDS_LIB"standard";
"B \NAC \NWC"11;
"S \NAC"
BN"7"188;
%"TAP"
"1","(4175,2750)","0","standard","I114";
;
HDL_TAP"TRUE"
BODY_TYPE"PLUMBING"
CDS_LIB"standard";
"B \NAC \NWC"11;
"S \NAC"
BN"6"187;
%"TAP"
"1","(4175,2800)","0","standard","I115";
;
HDL_TAP"TRUE"
BODY_TYPE"PLUMBING"
CDS_LIB"standard";
"B \NAC \NWC"11;
"S \NAC"
BN"5"186;
%"TAP"
"1","(4175,2900)","0","standard","I116";
;
HDL_TAP"TRUE"
BODY_TYPE"PLUMBING"
CDS_LIB"standard";
"B \NAC \NWC"11;
"S \NAC"
BN"3"185;
%"TAP"
"1","(4175,2850)","0","standard","I117";
;
HDL_TAP"TRUE"
BODY_TYPE"PLUMBING"
CDS_LIB"standard";
"B \NAC \NWC"11;
"S \NAC"
BN"4"92;
%"TAP"
"1","(4175,2950)","0","standard","I118";
;
HDL_TAP"TRUE"
BODY_TYPE"PLUMBING"
CDS_LIB"standard";
"B \NAC \NWC"11;
"S \NAC"
BN"2"93;
%"TAP"
"1","(4175,3000)","0","standard","I150";
;
HDL_TAP"TRUE"
BODY_TYPE"PLUMBING"
CDS_LIB"standard";
"B \NAC \NWC"11;
"S \NAC"
BN"1"94;
%"TAP"
"1","(4175,3050)","0","standard","I151";
;
HDL_TAP"TRUE"
BODY_TYPE"PLUMBING"
CDS_LIB"standard";
"B \NAC \NWC"11;
"S \NAC"
BN"0"95;
%"Q_CAP"
"2","(3825,4600)","0","pure_quanta","I152";
;
TOLERANCE"10%"
PART_NUMBER"CH4104K1B00"
VOLTAGE"25V"
MATERIAL"X7R"
VALUE"0.1UF"
PACK_TYPE"0402"
CDS_LIB"pure_quanta"
LOCATION"C24"
$SEC"1"
CDS_SEC"1";
"A"
$PN"1"102;
"B"
$PN"2"109;
%"Q_CAP"
"2","(3825,4550)","0","pure_quanta","I153";
;
VALUE"0.1UF"
PACK_TYPE"0402"
CDS_LIB"pure_quanta"
VOLTAGE"25V"
TOLERANCE"10%"
PART_NUMBER"CH4104K1B00"
MATERIAL"X7R"
LOCATION"C25"
$SEC"1"
CDS_SEC"1";
"A"
$PN"1"101;
"B"
$PN"2"110;
%"Q_RES"
"1","(-1475,-425)","0","pure_quanta","I2";
;
VALUE"4.7K"
MATERIAL"EMPTY"
PART_NUMBER"CS24702FB06"
CDS_LIB"pure_quanta"
TOLERANCE"1%"
WATTAGE"1/16W"
PACK_TYPE"0402LF"
LOCATION"R117"
$SEC"1"
CDS_SEC"1";
"B"
$PN"2"74;
"A"
$PN"1"4;
%"Q_RES"
"1","(4125,1050)","0","pure_quanta","I235";
;
MATERIAL"CHIP"
VALUE"33.2"
PACK_TYPE"0402LF"
WATTAGE"1/16W"
CDS_LIB"pure_quanta"
PART_NUMBER"CS03322FB03"
TOLERANCE"1%"
LOCATION"R146"
$SEC"1"
CDS_SEC"1";
"B"
$PN"2"18;
"A"
$PN"1"24;
%"Q_RES"
"1","(4125,1000)","0","pure_quanta","I236";
;
VALUE"33.2"
MATERIAL"CHIP"
PACK_TYPE"0402LF"
WATTAGE"1/16W"
CDS_LIB"pure_quanta"
PART_NUMBER"CS03322FB03"
TOLERANCE"1%"
LOCATION"R147"
$SEC"1"
CDS_SEC"1";
"B"
$PN"2"19;
"A"
$PN"1"25;
%"Q_CAP"
"1","(-2200,2625)","0","pure_quanta","I24";
;
TOLERANCE"10%"
VOLTAGE"50V"
MATERIAL"EMPTY"
PACK_TYPE"C0402"
PART_NUMBER"CH31006KB18"
VALUE"0.01UF"
CDS_LIB"pure_quanta"
LOCATION"C21"
$SEC"1"
CDS_SEC"1";
"B"
$PN"2"5;
"A"
$PN"1"1;
%"Q_RES"
"1","(-650,250)","0","pure_quanta","I244";
;
VALUE"33.2"
MATERIAL"CHIP"
PACK_TYPE"0402LF"
WATTAGE"1/16W"
CDS_LIB"pure_quanta"
PART_NUMBER"CS03322FB03"
TOLERANCE"1%"
LOCATION"R236"
$SEC"1"
CDS_SEC"1";
"B"
$PN"2"138;
"A"
$PN"1"72;
%"Q_RES"
"1","(-650,300)","0","pure_quanta","I245";
;
VALUE"33.2"
MATERIAL"CHIP"
PACK_TYPE"0402LF"
WATTAGE"1/16W"
CDS_LIB"pure_quanta"
PART_NUMBER"CS03322FB03"
TOLERANCE"1%"
LOCATION"R162"
$SEC"1"
CDS_SEC"1";
"B"
$PN"2"137;
"A"
$PN"1"71;
%"Q_RES"
"1","(-650,150)","0","pure_quanta","I248";
;
VALUE"33.2"
MATERIAL"CHIP"
CDS_LIB"pure_quanta"
TOLERANCE"1%"
PART_NUMBER"CS03322FB03"
WATTAGE"1/16W"
PACK_TYPE"0402LF"
LOCATION"R153"
$SEC"1"
CDS_SEC"1";
"B"
$PN"2"169;
"A"
$PN"1"73;
%"Q_RES"
"1","(-650,200)","0","pure_quanta","I249";
;
VALUE"33.2"
MATERIAL"CHIP"
CDS_LIB"pure_quanta"
TOLERANCE"1%"
PART_NUMBER"CS03322FB03"
WATTAGE"1/16W"
PACK_TYPE"0402LF"
LOCATION"R152"
$SEC"1"
CDS_SEC"1";
"B"
$PN"2"131;
"A"
$PN"1"168;
%"UNIVERSAL_POWER"
"1","(-2200,3000)","0","logical_power","I25";
;
HDL_POWER"P0V6_DDR_VREF_AUX"
CDS_LIB"logical_power";
"A"1;
%"Q_RES"
"1","(4375,250)","0","pure_quanta","I252";
;
MATERIAL"CHIP"
VALUE"33.2"
PACK_TYPE"0402LF"
WATTAGE"1/16W"
CDS_LIB"pure_quanta"
PART_NUMBER"CS03322FB03"
TOLERANCE"1%"
LOCATION"R423"
$SEC"1"
CDS_SEC"1";
"B"
$PN"2"41;
"A"
$PN"1"91;
%"Q_RES"
"1","(4375,200)","0","pure_quanta","I253";
;
MATERIAL"CHIP"
VALUE"33.2"
PACK_TYPE"0402LF"
WATTAGE"1/16W"
CDS_LIB"pure_quanta"
PART_NUMBER"CS03322FB03"
TOLERANCE"1%"
LOCATION"R424"
$SEC"1"
CDS_SEC"1";
"B"
$PN"2"40;
"A"
$PN"1"90;
%"Q_RES"
"1","(4375,150)","0","pure_quanta","I254";
;
MATERIAL"CHIP"
VALUE"33.2"
PACK_TYPE"0402LF"
WATTAGE"1/16W"
CDS_LIB"pure_quanta"
PART_NUMBER"CS03322FB03"
TOLERANCE"1%"
LOCATION"R425"
$SEC"1"
CDS_SEC"1";
"B"
$PN"2"39;
"A"
$PN"1"89;
%"Q_RES"
"1","(4375,100)","0","pure_quanta","I255";
;
MATERIAL"CHIP"
VALUE"33.2"
PACK_TYPE"0402LF"
WATTAGE"1/16W"
CDS_LIB"pure_quanta"
PART_NUMBER"CS03322FB03"
TOLERANCE"1%"
LOCATION"R426"
$SEC"1"
CDS_SEC"1";
"B"
$PN"2"46;
"A"
$PN"1"38;
%"UNIVERSAL_GND"
"1","(-1700,2200)","0","logical_power","I26";
;
HDL_POWER"GND"
CDS_LIB"logical_power";
"A"5;
%"Q_RES"
"1","(-775,-1150)","0","pure_quanta","I268";
;
VALUE"33.2"
MATERIAL"CHIP"
PACK_TYPE"0402LF"
WATTAGE"1/16W"
CDS_LIB"pure_quanta"
PART_NUMBER"CS03322FB03"
TOLERANCE"1%"
LOCATION"R168"
$SEC"1"
CDS_SEC"1";
"B"
$PN"2"170;
"A"
$PN"1"139;
%"Q_RES"
"1","(4775,-450)","0","pure_quanta","I274";
;
VALUE"33.2"
MATERIAL"CHIP"
PACK_TYPE"0402LF"
WATTAGE"1/16W"
CDS_LIB"pure_quanta"
PART_NUMBER"CS03322FB03"
TOLERANCE"1%"
LOCATION"R567"
$SEC"1"
CDS_SEC"1";
"B"
$PN"2"76;
"A"
$PN"1"145;
%"Q_RES"
"1","(4775,-500)","0","pure_quanta","I275";
;
VALUE"33.2"
MATERIAL"CHIP"
PACK_TYPE"0402LF"
WATTAGE"1/16W"
CDS_LIB"pure_quanta"
PART_NUMBER"CS03322FB03"
TOLERANCE"1%"
LOCATION"R570"
$SEC"1"
CDS_SEC"1";
"B"
$PN"2"143;
"A"
$PN"1"75;
%"Q_RES"
"1","(4775,-400)","0","pure_quanta","I276";
;
VALUE"33.2"
MATERIAL"CHIP"
PACK_TYPE"0402LF"
WATTAGE"1/16W"
CDS_LIB"pure_quanta"
PART_NUMBER"CS03322FB03"
TOLERANCE"1%"
LOCATION"R93"
$SEC"1"
CDS_SEC"1";
"B"
$PN"2"77;
"A"
$PN"1"146;
%"Q_RES"
"1","(4775,-350)","0","pure_quanta","I277";
;
VALUE"33.2"
MATERIAL"CHIP"
PACK_TYPE"0402LF"
WATTAGE"1/16W"
CDS_LIB"pure_quanta"
PART_NUMBER"CS03322FB03"
TOLERANCE"1%"
LOCATION"R71"
$SEC"1"
CDS_SEC"1";
"B"
$PN"2"108;
"A"
$PN"1"144;
%"Q_CAP"
"1","(-1550,2625)","0","pure_quanta","I28";
;
PART_NUMBER"CH4104K1B00"
VALUE"0.1UF"
TOLERANCE"10%"
MATERIAL"X7R"
VOLTAGE"25V"
PACK_TYPE"0402"
CDS_LIB"pure_quanta"
LOCATION"C23"
$SEC"1"
CDS_SEC"1";
"B"
$PN"2"5;
"A"
$PN"1"1;
%"Q_RES"
"1","(-1475,-375)","0","pure_quanta","I3";
;
MATERIAL"CHIP"
VALUE"4.7K"
PACK_TYPE"0402LF"
WATTAGE"1/16W"
TOLERANCE"1%"
CDS_LIB"pure_quanta"
PART_NUMBER"CS24702FB06"
LOCATION"R116"
$SEC"1"
CDS_SEC"1";
"B"
$PN"2"166;
"A"
$PN"1"4;
%"Q_RES"
"1","(4125,1700)","0","pure_quanta","I314";
;
VALUE"33.2"
MATERIAL"CHIP"
PACK_TYPE"0402LF"
WATTAGE"1/16W"
CDS_LIB"pure_quanta"
PART_NUMBER"CS03322FB03"
TOLERANCE"1%"
LOCATION"R394"
$SEC"1"
CDS_SEC"1";
"B"
$PN"2"37;
"A"
$PN"1"47;
%"Q_RES"
"1","(4125,1750)","0","pure_quanta","I315";
;
VALUE"33.2"
MATERIAL"CHIP"
PACK_TYPE"0402LF"
WATTAGE"1/16W"
CDS_LIB"pure_quanta"
PART_NUMBER"CS03322FB03"
TOLERANCE"1%"
LOCATION"R165"
$SEC"1"
CDS_SEC"1";
"B"
$PN"2"85;
"A"
$PN"1"48;
%"Q_RES"
"1","(4125,1650)","0","pure_quanta","I316";
;
VALUE"33.2"
MATERIAL"CHIP"
PACK_TYPE"0402LF"
WATTAGE"1/16W"
CDS_LIB"pure_quanta"
PART_NUMBER"CS03322FB03"
TOLERANCE"1%"
LOCATION"R589"
$SEC"1"
CDS_SEC"1";
"B"
$PN"2"36;
"A"
$PN"1"13;
%"Q_RES"
"1","(4125,1600)","0","pure_quanta","I317";
;
MATERIAL"CHIP"
VALUE"33.2"
PACK_TYPE"0402LF"
WATTAGE"1/16W"
CDS_LIB"pure_quanta"
PART_NUMBER"CS03322FB03"
TOLERANCE"1%"
LOCATION"R590"
$SEC"1"
CDS_SEC"1";
"B"
$PN"2"35;
"A"
$PN"1"14;
%"Q_RES"
"1","(2075,-1000)","0","pure_quanta","I318";
;
MATERIAL"CHIP"
VALUE"33.2"
PACK_TYPE"0402LF"
WATTAGE"1/16W"
CDS_LIB"pure_quanta"
PART_NUMBER"CS03322FB03"
TOLERANCE"1%"
LOCATION"R582"
$SEC"1"
CDS_SEC"1";
"B"
$PN"2"105;
"A"
$PN"1"141;
%"Q_RES"
"1","(2075,-1050)","0","pure_quanta","I319";
;
MATERIAL"CHIP"
VALUE"33.2"
PACK_TYPE"0402LF"
WATTAGE"1/16W"
CDS_LIB"pure_quanta"
PART_NUMBER"CS03322FB03"
TOLERANCE"1%"
LOCATION"R583"
$SEC"1"
CDS_SEC"1";
"B"
$PN"2"106;
"A"
$PN"1"140;
%"Q_RES"
"1","(2075,-1100)","0","pure_quanta","I320";
;
MATERIAL"CHIP"
VALUE"33.2"
PACK_TYPE"0402LF"
WATTAGE"1/16W"
CDS_LIB"pure_quanta"
PART_NUMBER"CS03322FB03"
TOLERANCE"1%"
LOCATION"R584"
$SEC"1"
CDS_SEC"1";
"B"
$PN"2"103;
"A"
$PN"1"171;
%"Q_RES"
"1","(2075,-950)","0","pure_quanta","I321";
;
MATERIAL"CHIP"
VALUE"33.2"
PACK_TYPE"0402LF"
WATTAGE"1/16W"
CDS_LIB"pure_quanta"
PART_NUMBER"CS03322FB03"
TOLERANCE"1%"
LOCATION"R580"
$SEC"1"
CDS_SEC"1";
"B"
$PN"2"104;
"A"
$PN"1"142;
%"Q_RES"
"1","(-850,1950)","0","pure_quanta","I33";
;
PART_NUMBER"CS03322FB03"
MATERIAL"CHIP"
TOLERANCE"1%"
WATTAGE"1/16W"
VALUE"33.2"
PACK_TYPE"0402LF"
CDS_LIB"pure_quanta"
LOCATION"R120"
$SEC"1"
CDS_SEC"1";
"B"
$PN"2"49;
"A"
$PN"1"158;
%"Q_RES"
"1","(-850,2000)","0","pure_quanta","I34";
;
MATERIAL"CHIP"
VALUE"33.2"
TOLERANCE"1%"
PART_NUMBER"CS03322FB03"
WATTAGE"1/16W"
PACK_TYPE"0402LF"
CDS_LIB"pure_quanta"
LOCATION"R119"
$SEC"1"
CDS_SEC"1";
"B"
$PN"2"51;
"A"
$PN"1"162;
%"UNIVERSAL_POWER"
"1","(-2775,3425)","0","logical_power","I349";
;
HDL_POWER"P3V3_AUX"
CDS_LIB"logical_power";
"A"2;
%"UNIVERSAL_GND"
"1","(-800,2200)","5","logical_power","I35";
;
HDL_POWER"GND"
CDS_LIB"logical_power";
"A"6;
%"Q_RES"
"1","(-2550,3300)","0","pure_quanta","I350";
;
VALUE"4.7K"
MATERIAL"CHIP"
PACK_TYPE"0402LF"
WATTAGE"1/16W"
TOLERANCE"1%"
CDS_LIB"pure_quanta"
PART_NUMBER"CS24702FB06"
LOCATION"R62"
$SEC"1"
CDS_SEC"1";
"B"
$PN"2"156;
"A"
$PN"1"2;
%"Q_RES"
"1","(-850,750)","0","pure_quanta","I353";
;
MATERIAL"CHIP"
VALUE"33.2"
PACK_TYPE"0402LF"
WATTAGE"1/16W"
CDS_LIB"pure_quanta"
PART_NUMBER"CS03322FB03"
TOLERANCE"1%"
LOCATION"R705"
$SEC"1"
CDS_SEC"1";
"B"
$PN"2"132;
"A"
$PN"1"68;
%"Q_RES"
"1","(-2550,3225)","0","pure_quanta","I354";
;
MATERIAL"CHIP"
VALUE"4.7K"
PACK_TYPE"0402LF"
WATTAGE"1/16W"
TOLERANCE"1%"
CDS_LIB"pure_quanta"
PART_NUMBER"CS24702FB06"
LOCATION"R706"
$SEC"1"
CDS_SEC"1";
"B"
$PN"2"157;
"A"
$PN"1"2;
%"Q_RES"
"1","(-650,500)","0","pure_quanta","I379";
;
VALUE"33.2"
MATERIAL"CHIP"
PACK_TYPE"0402LF"
WATTAGE"1/16W"
CDS_LIB"pure_quanta"
PART_NUMBER"CS03322FB03"
TOLERANCE"1%"
LOCATION"R148"
$SEC"1"
CDS_SEC"1";
"B"
$PN"2"133;
"A"
$PN"1"163;
%"Q_RES"
"1","(-650,450)","0","pure_quanta","I380";
;
MATERIAL"CHIP"
VALUE"33.2"
PACK_TYPE"0402LF"
WATTAGE"1/16W"
CDS_LIB"pure_quanta"
PART_NUMBER"CS03322FB03"
TOLERANCE"1%"
LOCATION"R150"
$SEC"1"
CDS_SEC"1";
"B"
$PN"2"134;
"A"
$PN"1"69;
%"Q_RES"
"1","(-650,400)","0","pure_quanta","I381";
;
MATERIAL"CHIP"
VALUE"33.2"
PACK_TYPE"0402LF"
WATTAGE"1/16W"
CDS_LIB"pure_quanta"
PART_NUMBER"CS03322FB03"
TOLERANCE"1%"
LOCATION"R151"
$SEC"1"
CDS_SEC"1";
"B"
$PN"2"135;
"A"
$PN"1"164;
%"Q_RES"
"1","(-650,350)","0","pure_quanta","I382";
;
VALUE"33.2"
MATERIAL"CHIP"
PACK_TYPE"0402LF"
WATTAGE"1/16W"
CDS_LIB"pure_quanta"
PART_NUMBER"CS03322FB03"
TOLERANCE"1%"
LOCATION"R433"
$SEC"1"
CDS_SEC"1";
"B"
$PN"2"136;
"A"
$PN"1"70;
%"Q_RES"
"1","(4125,550)","0","pure_quanta","I385";
;
VALUE"33.2"
MATERIAL"CHIP"
PACK_TYPE"0402LF"
WATTAGE"1/16W"
CDS_LIB"pure_quanta"
PART_NUMBER"CS03322FB03"
TOLERANCE"1%"
LOCATION"R137"
$SEC"1"
CDS_SEC"1";
"B"
$PN"2"43;
"A"
$PN"1"147;
%"Q_RES"
"1","(4125,500)","0","pure_quanta","I386";
;
VALUE"33.2"
MATERIAL"CHIP"
PACK_TYPE"0402LF"
WATTAGE"1/16W"
CDS_LIB"pure_quanta"
PART_NUMBER"CS03322FB03"
TOLERANCE"1%"
LOCATION"R144"
$SEC"1"
CDS_SEC"1";
"B"
$PN"2"42;
"A"
$PN"1"88;
%"UNIVERSAL_GND"
"1","(2250,-525)","0","logical_power","I389";
;
CDS_LIB"logical_power"
HDL_POWER"GND";
"A"7;
%"Q_RES"
"1","(2550,-400)","2","pure_quanta","I390";
;
TOLERANCE"1%"
MATERIAL"EMPTY"
VALUE"100K"
WATTAGE"1/16W"
PACK_TYPE"0402LF"
PART_NUMBER"CS41002FB09"
SEC_TYPE"0402LF"
CDS_LIB"pure_quanta"
LOCATION"R820"
SEC"1";
"B"
$PN"2"7;
"A"
$PN"1"38;
%"Q_RES"
"1","(2550,-350)","2","pure_quanta","I391";
;
MATERIAL"EMPTY"
VALUE"100K"
PACK_TYPE"0402LF"
WATTAGE"1/16W"
PART_NUMBER"CS41002FB09"
TOLERANCE"1%"
SEC_TYPE"0402LF"
CDS_LIB"pure_quanta"
LOCATION"R819"
SEC"1";
"B"
$PN"2"7;
"A"
$PN"1"89;
%"Q_RES"
"1","(2550,-300)","2","pure_quanta","I392";
;
MATERIAL"EMPTY"
VALUE"100K"
PACK_TYPE"0402LF"
WATTAGE"1/16W"
PART_NUMBER"CS41002FB09"
TOLERANCE"1%"
SEC_TYPE"0402LF"
CDS_LIB"pure_quanta"
LOCATION"R818"
SEC"1";
"B"
$PN"2"7;
"A"
$PN"1"90;
%"Q_RES"
"1","(2550,-250)","2","pure_quanta","I393";
;
VALUE"100K"
MATERIAL"EMPTY"
PACK_TYPE"0402LF"
WATTAGE"1/16W"
PART_NUMBER"CS41002FB09"
TOLERANCE"1%"
SEC_TYPE"0402LF"
CDS_LIB"pure_quanta"
LOCATION"R817"
SEC"1";
"B"
$PN"2"7;
"A"
$PN"1"91;
%"Q_RES"
"1","(-1475,-325)","0","pure_quanta","I4";
;
VALUE"4.7K"
MATERIAL"EMPTY"
PART_NUMBER"CS24702FB06"
CDS_LIB"pure_quanta"
TOLERANCE"1%"
WATTAGE"1/16W"
PACK_TYPE"0402LF"
LOCATION"R115"
$SEC"1"
CDS_SEC"1";
"B"
$PN"2"165;
"A"
$PN"1"4;
%"Q_CAP"
"2","(3825,4150)","0","pure_quanta","I428";
;
VALUE"0.1UF"
CDS_LIB"pure_quanta"
PACK_TYPE"0402"
VOLTAGE"25V"
TOLERANCE"10%"
PART_NUMBER"CH4104K1B00"
MATERIAL"X7R"
$LOCATION"C272"
CDS_LOCATION"C272"
$SEC"1"
CDS_SEC"1";
"A"
$PN"1"154;
"B"
$PN"2"160;
%"Q_CAP"
"2","(3825,4200)","0","pure_quanta","I429";
;
PART_NUMBER"CH4104K1B00"
PACK_TYPE"0402"
MATERIAL"X7R"
VALUE"0.1UF"
TOLERANCE"10%"
VOLTAGE"25V"
CDS_LIB"pure_quanta"
$LOCATION"C271"
CDS_LOCATION"C271"
$SEC"1"
CDS_SEC"1";
"A"
$PN"1"100;
"B"
$PN"2"161;
%"AST2600A3GP"
"1","(1825,2250)","0","pure_quanta","I436";
;
MATERIAL"IC"
VALUE"AST2600A3-GP"
PART_TYPE"SMLF"
PART_NUMBER"AJ026000T06"
NEEDS_NO_SIZE"TRUE"
CDS_LMAN_SYM_OUTLINE"-900,2400,900,-2400"
CDS_LIB"pure_quanta"
LOCATION"U5"
$SEC"1"
CDS_SEC"1";
"GPIOS3||OSCCLK"
$PN"R24"87;
"GPIOS2||PEWAKE#"
$PN"T26"98;
"GPIOH7||SGPS1I1||SDA16"
$PN"E18"169;
"GPIOH6||SGPS1I0||SCL16"
$PN"C17"131;
"GPIOH5||SGPS1LD||SDA15"
$PN"B17"138;
"GPIOH4||SGPS1CK||SCL15"
$PN"D18"137;
"GPIOH3||SGPM1I"
$PN"A17"136;
"GPIOH2||SGPM1O"
$PN"C18"135;
"GPIOH1||SGPM1LD"
$PN"B18"134;
"GPIOH0||SGPM1CK"
$PN"A18"133;
"GPIOA5||MAC2LINK||SDA13||SGPM2LD||SGPS2LD"
$PN"L24"90;
"GPIOA4||MAC1LINK||SCL13||SGPM2CK||SGPS2CK"
$PN"K26"91;
"GPIOA7||MAC4LINK||SDA14||SGPM2I||SGPS2I1"
$PN"K25"38;
"GPIOA6||MAC3LINK||SCL14||SGPM2O||SGPS2I0"
$PN"L23"89;
"GPIOA3||SDA12||MDIO4"
$PN"K24"88;
"GPIOA2||SCL12||MDC4"
$PN"L26"147;
"GPIOA1||SDA11||MDIO3"
$PN"M25"44;
"GPIOA0||SCL11||MDC3"
$PN"M24"45;
"GPIOL3||SDA10"
$PN"A13"23;
"GPIOL2||SCL10"
$PN"E15"22;
"GPIOL1||SDA9"
$PN"A14"21;
"GPIOL0||SCL9"
$PN"D15"20;
"DPTXN1"
$PN"AA2"194;
"DPTXP1"
$PN"AB2"195;
"DPHPD"
$PN"C7"123;
"DPAUXN"
$PN"AB3"122;
"DPAUXP"
$PN"AC3"121;
"DPTXN0"
$PN"AB1"196;
"DPTXP0"
$PN"AC1"197;
"RCTXN"
$PN"AF3"154;
"RCTXP"
$PN"AF2"100;
"RCRXN"
$PN"AD3"198;
"RCRXP"
$PN"AD2"199;
"RCREFCLKN"
$PN"AE2"200;
"RCREFCLKP"
$PN"AE1"201;
"GPIOK7||SDA8"
$PN"E12"25;
"GPIOK1||SDA5"
$PN"C11"30;
"MCKE"
$PN"L5"178;
"GPIOW1||LAD1||ESPID1"
$PN"AB8"211;
"GPIOJ5||HVI3C5SDA||SDA3"
$PN"A19"14;
"GPIOW2||LAD2||ESPID2"
$PN"AC8"213;
"GPIOJ1||HVI3C3SDA||SDA1"
$PN"A20"83;
"GPIOW3||LAD3||ESPID3"
$PN"AC7"212;
"MODT"
$PN"J1"97;
"GPIOK0||SCL5"
$PN"A11"17;
"MA7"
$PN"M2"188;
"GPIOJ6||HVI3C6SCL||SCL4"
$PN"C20"15;
"MWE# \B"
$PN"G5"176;
"MA2"
$PN"F1"93;
"MCK"
$PN"K2"184;
"GPIOW0||LAD0||ESPID0"
$PN"AB7"210;
"MCAS# \B"
$PN"J4"177;
"GPIOJ3||HVI3C4SDA||SDA2"
$PN"D20"47;
"GPIOK2||SCL6"
$PN"D12"31;
"MA1"
$PN"K5"94;
"GPIOJ4||HVI3C5SCL||SCL3"
$PN"C19"13;
"MA9"
$PN"N1"190;
"GPIOK4||SCL7"
$PN"D11"33;
"MA4"
$PN"J3"92;
"MRAS# \B"
$PN"J5"183;
"MA10"
$PN"F2"191;
"GPIOK6||SCL8"
$PN"F13"24;
"GPIOJ0||HVI3C3SCL||SCL1"
$PN"B20"84;
"MA15||MBG1"
$PN"M3"150;
"GPIOK5||SDA7"
$PN"E11"26;
"MDM1"
$PN"R5"148;
"MA12"
$PN"L4"206;
"MA8"
$PN"M1"189;
"MCS# \B"
$PN"H2"96;
"MA5"
$PN"L1"186;
"MA6"
$PN"M5"187;
"GPIOJ7||HVI3C6SDA||SDA4"
$PN"D19"16;
"MDM0"
$PN"N3"149;
"MA11"
$PN"G1"152;
"MBA0"
$PN"G4"175;
"GPIOK3||SDA6"
$PN"E13"32;
"MA13"
$PN"K3"207;
"MA0"
$PN"F3"95;
"GPIOJ2||HVI3C4SCL||SCL2"
$PN"E19"48;
"MBA2||MBG0"
$PN"G3"192;
"MA14||MACT#"
$PN"H1"151;
"MA3"
$PN"H3"185;
"MBA1"
$PN"H5"153;
"MCK# \B"
$PN"K1"193;
"MVREF_U5"
$PN"U5"1;
"PERXN"
$PN"AF6"202;
"PERXP"
$PN"AF5"203;
"PEREFCLKN"
$PN"AD6"204;
"PEREFCLKP"
$PN"AD5"155;
"PERST# \B"
$PN"A7"205;
"PETXN"
$PN"AE5"101;
"PETXP"
$PN"AE4"102;
"GPIOG7||RXD9||SD2WP#||SALT16"
$PN"B21"132;
"GPIOG6||TXD9||SD2CD#||SALT15"
$PN"D21"67;
"GPIOG5||RXD8||SD2DAT3||SALT14"
$PN"E20"66;
"GPIOG4||TXD8||SD2DAT2||SALT13"
$PN"A21"65;
"GPIOG3||RXD7||SD2DAT1||SALT12"
$PN"A22"64;
"GPIOG2||TXD7||SD2DAT0||SALT11"
$PN"C21"63;
"GPIOG1||RXD6||SD2CMD||SALT10"
$PN"B22"99;
"GPIOG0||TXD6||SD2CLK||SALT9"
$PN"E21"62;
"GPIOF7||SD1WP#||PWM15"
$PN"A23"56;
"GPIOF6||SD1CD#||PWM14"
$PN"A24"55;
"GPIOF5||SD1DAT3||PWM13"
$PN"A25"54;
"GPIOF4||SD1DAT2||PWM12"
$PN"C22"53;
"GPIOF3||SD1DAT1||PWM11"
$PN"C23"61;
"GPIOF2||SD1DAT0||PWM10"
$PN"D23"60;
"GPIOF1||SD1CMD||PWM9"
$PN"E22"59;
"GPIOF0||SD1CLK||PWM8"
$PN"D22"50;
"GPIOW7||LPCRST#||ESPIRST#"
$PN"AD8"49;
"GPIOW6||LSIRQ#||ESPIALT#"
$PN"AD7"51;
"GPIOW5||LFRAME#||ESPICS#"
$PN"AF7"52;
"GPIOW4||LCLK||ESPICK"
$PN"AE7"58;
"MDQS1# \B"
$PN"V1"173;
"MDQS0# \B"
$PN"T1"129;
"MDQS1"
$PN"V2"128;
"MDQS0"
$PN"T2"127;
"MDQ15"
$PN"U3"126;
"MDQ14"
$PN"V4"125;
"MDQ13"
$PN"U4"118;
"MDQ12"
$PN"W4"111;
"MDQ11"
$PN"W3"112;
"MDQ10"
$PN"W1"113;
"MDQ9"
$PN"V3"114;
"MDQ8"
$PN"W2"115;
"MDQ7"
$PN"P3"116;
"MDQ6"
$PN"P2"117;
"MDQ5"
$PN"P1"119;
"MDQ4"
$PN"R1"182;
"MDQ3"
$PN"R3"181;
"MDQ2"
$PN"U1"180;
"MDQ1"
$PN"R4"179;
"MDQ0"
$PN"T3"120;
"MALERT# \B"
$PN"N4"208;
"MRESET# \B"
$PN"L3"174;
"MIOZ"
$PN"P5"209;
"MVREF_T5"
$PN"T5"1;
%"Q_RES"
"1","(-850,2100)","0","pure_quanta","I441";
;
MATERIAL"CHIP"
VALUE"33.2"
CDS_LIB"pure_quanta"
TOLERANCE"1%"
PART_NUMBER"CS03322FB03"
WATTAGE"1/16W"
PACK_TYPE"0402LF"
$LOCATION"R310"
CDS_LOCATION"R310"
$SEC"1"
CDS_SEC"1";
"B"
$PN"2"58;
"A"
$PN"1"124;
%"Q_RES"
"1","(3825,2100)","0","pure_quanta","I442";
;
VALUE"22"
PART_NUMBER"CS02202FB02"
MATERIAL"CHIP"
PACK_TYPE"0402LF"
WATTAGE"1/16W"
TOLERANCE"1%"
CDS_LIB"pure_quanta"
LOCATION"R128"
$SEC"1"
CDS_SEC"1";
"B"
$PN"2"78;
"A"
$PN"1"210;
%"Q_RES"
"1","(3825,1950)","0","pure_quanta","I443";
;
MATERIAL"CHIP"
VALUE"22"
CDS_LIB"pure_quanta"
PART_NUMBER"CS02202FB02"
TOLERANCE"1%"
WATTAGE"1/16W"
PACK_TYPE"0402LF"
LOCATION"R131"
$SEC"1"
CDS_SEC"1";
"B"
$PN"2"81;
"A"
$PN"1"212;
%"Q_RES"
"1","(3825,2000)","0","pure_quanta","I444";
;
VALUE"22"
MATERIAL"CHIP"
CDS_LIB"pure_quanta"
PACK_TYPE"0402LF"
WATTAGE"1/16W"
TOLERANCE"1%"
PART_NUMBER"CS02202FB02"
LOCATION"R130"
$SEC"1"
CDS_SEC"1";
"B"
$PN"2"80;
"A"
$PN"1"213;
%"Q_RES"
"1","(3825,2050)","0","pure_quanta","I445";
;
VALUE"22"
MATERIAL"CHIP"
PART_NUMBER"CS02202FB02"
TOLERANCE"1%"
WATTAGE"1/16W"
PACK_TYPE"0402LF"
CDS_LIB"pure_quanta"
LOCATION"R129"
$SEC"1"
CDS_SEC"1";
"B"
$PN"2"79;
"A"
$PN"1"211;
%"Q_RES"
"1","(-850,2050)","0","pure_quanta","I447";
;
MATERIAL"CHIP"
VALUE"33.2"
PACK_TYPE"0402LF"
WATTAGE"1/16W"
PART_NUMBER"CS03322FB03"
TOLERANCE"1%"
CDS_LIB"pure_quanta"
$LOCATION"R311"
CDS_LOCATION"R311"
$SEC"1"
CDS_SEC"1";
"B"
$PN"2"52;
"A"
$PN"1"130;
%"Q_CAP"
"1","(-1875,2625)","0","pure_quanta","I448";
;
PACK_TYPE"0402"
VALUE"0.1UF"
VOLTAGE"25V"
MATERIAL"X7R"
PART_NUMBER"CH4104K1B00"
TOLERANCE"10%"
CDS_LIB"pure_quanta"
LOCATION"C22"
$SEC"1"
CDS_SEC"1";
"B"
$PN"2"5;
"A"
$PN"1"1;
%"Q_RES"
"1","(4600,-950)","0","pure_quanta","I454";
;
VALUE"4.7K"
MATERIAL"EMPTY"
PART_NUMBER"CS24702FB06"
TOLERANCE"1%"
WATTAGE"1/16W"
PACK_TYPE"0402LF"
CDS_LIB"pure_quanta"
$LOCATION"R400"
CDS_LOCATION"R400"
$SEC"1"
CDS_SEC"1";
"B"
$PN"2"107;
"A"
$PN"1"3;
%"VCCAUX15"
"1","(4200,-800)","0","logical_power","I455";
;
HDL_POWER"P3V3_AUX"
CDS_LIB"logical_power";
"A"3;
%"Q_RES"
"2","(-1275,-625)","0","pure_quanta","I456";
;
PART_NUMBER"CS34702FB01"
PACK_TYPE"0402LF"
VALUE"47K"
TOLERANCE"1%"
WATTAGE"1/16W"
MATERIAL"CHIP"
CDS_LIB"pure_quanta"
$LOCATION"R312"
CDS_LOCATION"R312"
$SEC"1"
CDS_SEC"1";
"A"
$PN"1"74;
"B"
$PN"2"8;
%"UNIVERSAL_GND"
"1","(-1275,-825)","0","logical_power","I457";
;
HDL_POWER"GND"
CDS_LIB"logical_power";
"A"8;
%"Q_RES"
"1","(-1400,25)","0","pure_quanta","I458";
;
MATERIAL"CHIP"
VALUE"33.2"
CDS_LIB"pure_quanta"
PACK_TYPE"0402LF"
WATTAGE"1/16W"
PART_NUMBER"CS03322FB03"
TOLERANCE"1%"
$LOCATION"R880"
CDS_LOCATION"R880"
$SEC"1"
CDS_SEC"1";
"B"
$PN"2"73;
"A"
$PN"1"167;
%"Q_RES"
"1","(-200,2200)","0","pure_quanta","I46";
;
PART_NUMBER"CS12402FB01"
VALUE"240"
TOLERANCE"1%"
MATERIAL"CHIP"
WATTAGE"1/16W"
PACK_TYPE"0402LF"
CDS_LIB"pure_quanta"
LOCATION"R127"
$SEC"1"
CDS_SEC"1";
"B"
$PN"2"209;
"A"
$PN"1"6;
%"TAP"
"1","(-75,2850)","2","standard","I47";
;
HDL_TAP"TRUE"
BODY_TYPE"PLUMBING"
CDS_LIB"standard";
"B \NAC \NWC"12;
"S \NAC"
BN"15"126;
%"Q_RES"
"1","(-850,1100)","0","pure_quanta","I473";
;
VALUE"33.2"
MATERIAL"CHIP"
TOLERANCE"1%"
PART_NUMBER"CS03322FB03"
CDS_LIB"pure_quanta"
WATTAGE"1/16W"
PACK_TYPE"0402LF"
LOCATION"R761"
$SEC"1"
CDS_SEC"1";
"B"
$PN"2"62;
"A"
$PN"1"57;
%"Q_RES"
"1","(-850,1050)","0","pure_quanta","I474";
;
MATERIAL"CHIP"
VALUE"33.2"
TOLERANCE"1%"
PART_NUMBER"CS03322FB03"
CDS_LIB"pure_quanta"
WATTAGE"1/16W"
PACK_TYPE"0402LF"
LOCATION"R762"
$SEC"1"
CDS_SEC"1";
"B"
$PN"2"99;
"A"
$PN"1"159;
%"TAP"
"1","(-75,2900)","2","standard","I48";
;
HDL_TAP"TRUE"
BODY_TYPE"PLUMBING"
CDS_LIB"standard";
"B \NAC \NWC"12;
"S \NAC"
BN"14"125;
%"TAP"
"1","(-75,2950)","2","standard","I49";
;
HDL_TAP"TRUE"
BODY_TYPE"PLUMBING"
CDS_LIB"standard";
"B \NAC \NWC"12;
"S \NAC"
BN"13"118;
%"UNIVERSAL_GND"
"1","(-1500,4675)","0","logical_power","I50";
;
CDS_LIB"logical_power"
HDL_POWER"GND";
"A"10;
%"Q_RES"
"1","(-575,3800)","0","pure_quanta","I508";
;
PART_NUMBER"CS41002FB09"
VALUE"100K"
MATERIAL"CHIP"
CDS_LIB"pure_quanta"
PACK_TYPE"0402LF"
WATTAGE"1/16W"
TOLERANCE"1%"
$LOCATION"R387"
CDS_LOCATION"R387"
$SEC"1"
CDS_SEC"1";
"B"
$PN"2"123;
"A"
$PN"1"9;
%"UNIVERSAL_GND"
"1","(-1550,3600)","0","logical_power","I509";
;
HDL_POWER"GND"
CDS_LIB"logical_power";
"A"9;
%"Q_RES"
"1","(-1400,75)","0","pure_quanta","I510";
;
VALUE"200"
MATERIAL"CHIP"
PART_NUMBER"CS12002FB06"
PACK_TYPE"0402LF"
WATTAGE"1/16W"
TOLERANCE"1%"
CDS_LIB"pure_quanta"
LOCATION"R879"
$SEC"1"
CDS_SEC"1";
"B"
$PN"2"168;
"A"
$PN"1"172;
%"Q_RES"
"1","(4125,1500)","0","pure_quanta","I512";
;
VALUE"33.2"
MATERIAL"CHIP"
TOLERANCE"1%"
PART_NUMBER"CS03322FB03"
CDS_LIB"pure_quanta"
WATTAGE"1/16W"
PACK_TYPE"0402LF"
LOCATION"R139"
$SEC"1"
CDS_SEC"1";
"B"
$PN"2"29;
"A"
$PN"1"16;
%"Q_RES"
"1","(4125,1550)","0","pure_quanta","I513";
;
MATERIAL"CHIP"
VALUE"40.2"
CDS_LIB"pure_quanta"
TOLERANCE"1%"
PACK_TYPE"0402LF"
WATTAGE"1/16W"
PART_NUMBER"CS04022FB28"
LOCATION"R138"
$SEC"1"
CDS_SEC"1";
"B"
$PN"2"34;
"A"
$PN"1"15;
%"Q_RES"
"1","(-1150,4800)","0","pure_quanta","I53";
;
TOLERANCE"1%"
PACK_TYPE"0402LF"
WATTAGE"1/16W"
VALUE"100K"
PART_NUMBER"CS41002FB09"
MATERIAL"CHIP"
CDS_LIB"pure_quanta"
LOCATION"R118"
$SEC"1"
CDS_SEC"1";
"B"
$PN"2"205;
"A"
$PN"1"10;
%"TAP"
"1","(-75,3050)","2","standard","I58";
;
HDL_TAP"TRUE"
BODY_TYPE"PLUMBING"
CDS_LIB"standard";
"B \NAC \NWC"12;
"S \NAC"
BN"11"112;
%"TAP"
"1","(-75,3000)","2","standard","I59";
;
HDL_TAP"TRUE"
BODY_TYPE"PLUMBING"
CDS_LIB"standard";
"B \NAC \NWC"12;
"S \NAC"
BN"12"111;
%"TAP"
"1","(-75,3100)","2","standard","I60";
;
HDL_TAP"TRUE"
BODY_TYPE"PLUMBING"
CDS_LIB"standard";
"B \NAC \NWC"12;
"S \NAC"
BN"10"113;
%"TAP"
"1","(-75,3150)","2","standard","I61";
;
HDL_TAP"TRUE"
BODY_TYPE"PLUMBING"
CDS_LIB"standard";
"B \NAC \NWC"12;
"S \NAC"
BN"9"114;
%"TAP"
"1","(-75,3200)","2","standard","I62";
;
HDL_TAP"TRUE"
BODY_TYPE"PLUMBING"
CDS_LIB"standard";
"B \NAC \NWC"12;
"S \NAC"
BN"8"115;
%"TAP"
"1","(-75,3250)","2","standard","I63";
;
HDL_TAP"TRUE"
BODY_TYPE"PLUMBING"
CDS_LIB"standard";
"B \NAC \NWC"12;
"S \NAC"
BN"7"116;
%"TAP"
"1","(-75,3300)","2","standard","I64";
;
HDL_TAP"TRUE"
BODY_TYPE"PLUMBING"
CDS_LIB"standard";
"B \NAC \NWC"12;
"S \NAC"
BN"6"117;
%"TAP"
"1","(-75,3350)","2","standard","I65";
;
HDL_TAP"TRUE"
BODY_TYPE"PLUMBING"
CDS_LIB"standard";
"B \NAC \NWC"12;
"S \NAC"
BN"5"119;
%"TAP"
"1","(-75,3400)","2","standard","I66";
;
HDL_TAP"TRUE"
BODY_TYPE"PLUMBING"
CDS_LIB"standard";
"B \NAC \NWC"12;
"S \NAC"
BN"4"182;
%"TAP"
"1","(-75,3450)","2","standard","I67";
;
HDL_TAP"TRUE"
BODY_TYPE"PLUMBING"
CDS_LIB"standard";
"B \NAC \NWC"12;
"S \NAC"
BN"3"181;
%"TAP"
"1","(-75,3500)","2","standard","I68";
;
HDL_TAP"TRUE"
BODY_TYPE"PLUMBING"
CDS_LIB"standard";
"B \NAC \NWC"12;
"S \NAC"
BN"2"180;
%"TAP"
"1","(-75,3600)","2","standard","I69";
;
HDL_TAP"TRUE"
BODY_TYPE"PLUMBING"
CDS_LIB"standard";
"B \NAC \NWC"12;
"S \NAC"
BN"0"120;
%"TAP"
"1","(-75,3550)","2","standard","I70";
;
HDL_TAP"TRUE"
BODY_TYPE"PLUMBING"
CDS_LIB"standard";
"B \NAC \NWC"12;
"S \NAC"
BN"1"179;
%"Q_RES"
"1","(4125,1250)","0","pure_quanta","I88";
;
MATERIAL"CHIP"
VALUE"33.2"
PACK_TYPE"0402LF"
WATTAGE"1/16W"
CDS_LIB"pure_quanta"
PART_NUMBER"CS03322FB03"
TOLERANCE"1%"
LOCATION"R142"
$SEC"1"
CDS_SEC"1";
"B"
$PN"2"28;
"A"
$PN"1"31;
%"Q_RES"
"1","(4125,1200)","0","pure_quanta","I89";
;
MATERIAL"CHIP"
VALUE"33.2"
PACK_TYPE"0402LF"
WATTAGE"1/16W"
CDS_LIB"pure_quanta"
PART_NUMBER"CS03322FB03"
TOLERANCE"1%"
LOCATION"R143"
$SEC"1"
CDS_SEC"1";
"B"
$PN"2"27;
"A"
$PN"1"32;
%"Q_RES"
"1","(4125,1800)","0","pure_quanta","I97";
;
MATERIAL"CHIP"
VALUE"33.2"
PACK_TYPE"0402LF"
WATTAGE"1/16W"
CDS_LIB"pure_quanta"
PART_NUMBER"CS03322FB03"
TOLERANCE"1%"
LOCATION"R133"
$SEC"1"
CDS_SEC"1";
"B"
$PN"2"86;
"A"
$PN"1"83;
%"Q_RES"
"1","(4125,1850)","0","pure_quanta","I98";
;
VALUE"33.2"
MATERIAL"CHIP"
PACK_TYPE"0402LF"
WATTAGE"1/16W"
CDS_LIB"pure_quanta"
PART_NUMBER"CS03322FB03"
TOLERANCE"1%"
LOCATION"R132"
$SEC"1"
CDS_SEC"1";
"B"
$PN"2"82;
"A"
$PN"1"84;
END.
